(kicad_pcb
	(version 20260206)
	(generator "pcbnew")
	(generator_version "10.0")
	(general
		(thickness 1.6)
		(legacy_teardrops no)
	)
	(paper "A4")
	(title_block
		(title "01162023_DA0F0TEBIF0_F0T_Expander_BD_F_brd_V02_OCP.brd")
		(comment 1 "Grand Teton / footprints 1112-1117 of 9728")
	)
	(layers
		(0 "F.Cu" signal "TOP")
		(4 "In1.Cu" signal "GND")
		(6 "In2.Cu" signal "VCC")
		(8 "In3.Cu" signal "VCC1")
		(10 "In4.Cu" signal "GND1")
		(12 "In5.Cu" signal "IN1")
		(14 "In6.Cu" signal "GND2")
		(16 "In7.Cu" signal "IN2")
		(18 "In8.Cu" signal "GND3")
		(20 "In9.Cu" signal "IN3")
		(22 "In10.Cu" signal "GND4")
		(24 "In11.Cu" signal "IN4")
		(26 "In12.Cu" signal "GND5")
		(28 "In13.Cu" signal "IN5")
		(30 "In14.Cu" signal "GND6")
		(32 "In15.Cu" signal "IN6")
		(34 "In16.Cu" signal "GND7")
		(2 "B.Cu" signal "BOTTOM")
		(9 "F.Adhes" user "F.Adhesive")
		(11 "B.Adhes" user "B.Adhesive")
		(13 "F.Paste" user "Package Geometry/Pastemask Top")
		(15 "B.Paste" user "Package Geometry/Pastemask Bottom")
		(5 "F.SilkS" user "Ref Des/Silkscreen Top")
		(7 "B.SilkS" user "Ref Des/Silkscreen Bottom")
		(1 "F.Mask" user "Board Geometry/Soldermask Top")
		(3 "B.Mask" user "Board Geometry/Soldermask Bottom")
		(17 "Dwgs.User" user "User.Drawings")
		(19 "Cmts.User" user "User.Comments")
		(21 "Eco1.User" user "User.Eco1")
		(23 "Eco2.User" user "User.Eco2")
		(25 "Edge.Cuts" user "Board Geometry/Outline")
		(27 "Margin" user)
		(31 "F.CrtYd" user "Package Geometry/Place Bound Top")
		(29 "B.CrtYd" user "Package Geometry/Place Bound Bottom")
		(35 "F.Fab" user "Ref Des/Assembly Top")
		(33 "B.Fab" user "Ref Des/Assembly Bottom")
	)
	(footprint ""
		(layer "F.Cu")
		(at 71.73849 -44.341542 90)
		(property "Reference" "C209"
			(at 0 0 90)
			(layer "F.SilkS")
			(hide yes)
			(effects
				(font
					(size 1.27 1.27)
				)
			)
		)
		(property "Value" ""
			(at 0 0 90)
			(layer "F.Fab")
			(effects
				(font
					(size 1.27 1.27)
				)
			)
		)
		(duplicate_pad_numbers_are_jumpers no)
		(fp_line
			(start 0.7874 -0.4064)
			(end 0.7874 0.4064)
			(stroke
				(width 0.1524)
				(type default)
			)
			(layer "F.SilkS")
		)
		(fp_line
			(start -0.7874 -0.4064)
			(end 0.7874 -0.4064)
			(stroke
				(width 0.1524)
				(type default)
			)
			(layer "F.SilkS")
		)
		(fp_line
			(start 0.7874 0.4064)
			(end -0.7874 0.4064)
			(stroke
				(width 0.1524)
				(type default)
			)
			(layer "F.SilkS")
		)
		(fp_line
			(start -0.7874 0.4064)
			(end -0.7874 -0.4064)
			(stroke
				(width 0.1524)
				(type default)
			)
			(layer "F.SilkS")
		)
		(fp_line
			(start -0.12065 -0.305054)
			(end -0.12065 -0.2794)
			(stroke
				(width 0.1)
				(type default)
			)
			(layer "F.Fab")
		)
		(fp_line
			(start -0.67945 -0.305054)
			(end -0.12065 -0.305054)
			(stroke
				(width 0.1)
				(type default)
			)
			(layer "F.Fab")
		)
		(fp_line
			(start 0.67945 -0.3048)
			(end 0.67945 0.3048)
			(stroke
				(width 0.1)
				(type default)
			)
			(layer "F.Fab")
		)
		(fp_line
			(start 0.12065 -0.3048)
			(end 0.67945 -0.3048)
			(stroke
				(width 0.1)
				(type default)
			)
			(layer "F.Fab")
		)
		(fp_line
			(start 0.12065 -0.2794)
			(end 0.12065 -0.3048)
			(stroke
				(width 0.1)
				(type default)
			)
			(layer "F.Fab")
		)
		(fp_line
			(start -0.12065 -0.2794)
			(end 0.12065 -0.2794)
			(stroke
				(width 0.1)
				(type default)
			)
			(layer "F.Fab")
		)
		(fp_line
			(start 0.120396 0.2794)
			(end -0.12065 0.2794)
			(stroke
				(width 0.1)
				(type default)
			)
			(layer "F.Fab")
		)
		(fp_line
			(start -0.12065 0.2794)
			(end -0.12065 0.3048)
			(stroke
				(width 0.1)
				(type default)
			)
			(layer "F.Fab")
		)
		(fp_line
			(start 0.67945 0.3048)
			(end 0.120396 0.3048)
			(stroke
				(width 0.1)
				(type default)
			)
			(layer "F.Fab")
		)
		(fp_line
			(start 0.120396 0.3048)
			(end 0.120396 0.2794)
			(stroke
				(width 0.1)
				(type default)
			)
			(layer "F.Fab")
		)
		(fp_line
			(start -0.12065 0.3048)
			(end -0.67945 0.3048)
			(stroke
				(width 0.1)
				(type default)
			)
			(layer "F.Fab")
		)
		(fp_line
			(start -0.67945 0.3048)
			(end -0.67945 -0.305054)
			(stroke
				(width 0.1)
				(type default)
			)
			(layer "F.Fab")
		)
		(pad "1" smd circle
			(at -0.40005 0 90)
			(size 0 0)
			(layers "F.Cu" "F.Mask" "F.Paste")
			(net "P12V_SSD2_VIN_P")
		)
		(pad "2" smd circle
			(at 0.40005 0 90)
			(size 0 0)
			(layers "F.Cu" "F.Mask" "F.Paste")
			(net "P12V_SSD2_VIN_N")
		)
	)
	(footprint ""
		(layer "F.Cu")
		(at 263.904984 -347.997018 -90)
		(property "Reference" "R6655"
			(at 0 0 270)
			(layer "F.SilkS")
			(hide yes)
			(effects
				(font
					(size 1.27 1.27)
				)
			)
		)
		(property "Value" ""
			(at 0 0 270)
			(layer "F.Fab")
			(effects
				(font
					(size 1.27 1.27)
				)
			)
		)
		(duplicate_pad_numbers_are_jumpers no)
		(fp_line
			(start -0.7874 0.4064)
			(end -0.7874 -0.4064)
			(stroke
				(width 0.1524)
				(type default)
			)
			(layer "F.SilkS")
		)
		(fp_line
			(start 0.7874 0.4064)
			(end -0.7874 0.4064)
			(stroke
				(width 0.1524)
				(type default)
			)
			(layer "F.SilkS")
		)
		(fp_line
			(start -0.7874 -0.4064)
			(end 0.7874 -0.4064)
			(stroke
				(width 0.1524)
				(type default)
			)
			(layer "F.SilkS")
		)
		(fp_line
			(start 0.7874 -0.4064)
			(end 0.7874 0.4064)
			(stroke
				(width 0.1524)
				(type default)
			)
			(layer "F.SilkS")
		)
		(fp_line
			(start -0.67945 0.3048)
			(end -0.67945 -0.305054)
			(stroke
				(width 0.1)
				(type default)
			)
			(layer "F.Fab")
		)
		(fp_line
			(start -0.12065 0.3048)
			(end -0.67945 0.3048)
			(stroke
				(width 0.1)
				(type default)
			)
			(layer "F.Fab")
		)
		(fp_line
			(start 0.120396 0.3048)
			(end 0.120396 0.2794)
			(stroke
				(width 0.1)
				(type default)
			)
			(layer "F.Fab")
		)
		(fp_line
			(start 0.67945 0.3048)
			(end 0.120396 0.3048)
			(stroke
				(width 0.1)
				(type default)
			)
			(layer "F.Fab")
		)
		(fp_line
			(start -0.12065 0.2794)
			(end -0.12065 0.3048)
			(stroke
				(width 0.1)
				(type default)
			)
			(layer "F.Fab")
		)
		(fp_line
			(start 0.120396 0.2794)
			(end -0.12065 0.2794)
			(stroke
				(width 0.1)
				(type default)
			)
			(layer "F.Fab")
		)
		(fp_line
			(start -0.12065 -0.2794)
			(end 0.12065 -0.2794)
			(stroke
				(width 0.1)
				(type default)
			)
			(layer "F.Fab")
		)
		(fp_line
			(start 0.12065 -0.2794)
			(end 0.12065 -0.3048)
			(stroke
				(width 0.1)
				(type default)
			)
			(layer "F.Fab")
		)
		(fp_line
			(start 0.12065 -0.3048)
			(end 0.67945 -0.3048)
			(stroke
				(width 0.1)
				(type default)
			)
			(layer "F.Fab")
		)
		(fp_line
			(start 0.67945 -0.3048)
			(end 0.67945 0.3048)
			(stroke
				(width 0.1)
				(type default)
			)
			(layer "F.Fab")
		)
		(fp_line
			(start -0.67945 -0.305054)
			(end -0.12065 -0.305054)
			(stroke
				(width 0.1)
				(type default)
			)
			(layer "F.Fab")
		)
		(fp_line
			(start -0.12065 -0.305054)
			(end -0.12065 -0.2794)
			(stroke
				(width 0.1)
				(type default)
			)
			(layer "F.Fab")
		)
		(pad "1" smd circle
			(at -0.40005 0 270)
			(size 0 0)
			(layers "F.Cu" "F.Mask" "F.Paste")
			(net "A_HSC_LOW_DRAIN")
		)
		(pad "2" smd circle
			(at 0.40005 0 270)
			(size 0 0)
			(layers "F.Cu" "F.Mask" "F.Paste")
			(net "HSC_D_OC_R")
		)
	)
	(footprint ""
		(layer "F.Cu")
		(at 162.587686 -25.342342 -90)
		(property "Reference" "R425"
			(at 0 0 270)
			(layer "F.SilkS")
			(hide yes)
			(effects
				(font
					(size 1.27 1.27)
				)
			)
		)
		(property "Value" ""
			(at 0 0 270)
			(layer "F.Fab")
			(effects
				(font
					(size 1.27 1.27)
				)
			)
		)
		(duplicate_pad_numbers_are_jumpers no)
		(fp_line
			(start -0.7874 0.4064)
			(end -0.7874 -0.4064)
			(stroke
				(width 0.1524)
				(type default)
			)
			(layer "F.SilkS")
		)
		(fp_line
			(start 0.7874 0.4064)
			(end -0.7874 0.4064)
			(stroke
				(width 0.1524)
				(type default)
			)
			(layer "F.SilkS")
		)
		(fp_line
			(start -0.7874 -0.4064)
			(end 0.7874 -0.4064)
			(stroke
				(width 0.1524)
				(type default)
			)
			(layer "F.SilkS")
		)
		(fp_line
			(start 0.7874 -0.4064)
			(end 0.7874 0.4064)
			(stroke
				(width 0.1524)
				(type default)
			)
			(layer "F.SilkS")
		)
		(fp_line
			(start -0.67945 0.3048)
			(end -0.67945 -0.305054)
			(stroke
				(width 0.1)
				(type default)
			)
			(layer "F.Fab")
		)
		(fp_line
			(start -0.12065 0.3048)
			(end -0.67945 0.3048)
			(stroke
				(width 0.1)
				(type default)
			)
			(layer "F.Fab")
		)
		(fp_line
			(start 0.120396 0.3048)
			(end 0.120396 0.2794)
			(stroke
				(width 0.1)
				(type default)
			)
			(layer "F.Fab")
		)
		(fp_line
			(start 0.67945 0.3048)
			(end 0.120396 0.3048)
			(stroke
				(width 0.1)
				(type default)
			)
			(layer "F.Fab")
		)
		(fp_line
			(start -0.12065 0.2794)
			(end -0.12065 0.3048)
			(stroke
				(width 0.1)
				(type default)
			)
			(layer "F.Fab")
		)
		(fp_line
			(start 0.120396 0.2794)
			(end -0.12065 0.2794)
			(stroke
				(width 0.1)
				(type default)
			)
			(layer "F.Fab")
		)
		(fp_line
			(start -0.12065 -0.2794)
			(end 0.12065 -0.2794)
			(stroke
				(width 0.1)
				(type default)
			)
			(layer "F.Fab")
		)
		(fp_line
			(start 0.12065 -0.2794)
			(end 0.12065 -0.3048)
			(stroke
				(width 0.1)
				(type default)
			)
			(layer "F.Fab")
		)
		(fp_line
			(start 0.12065 -0.3048)
			(end 0.67945 -0.3048)
			(stroke
				(width 0.1)
				(type default)
			)
			(layer "F.Fab")
		)
		(fp_line
			(start 0.67945 -0.3048)
			(end 0.67945 0.3048)
			(stroke
				(width 0.1)
				(type default)
			)
			(layer "F.Fab")
		)
		(fp_line
			(start -0.67945 -0.305054)
			(end -0.12065 -0.305054)
			(stroke
				(width 0.1)
				(type default)
			)
			(layer "F.Fab")
		)
		(fp_line
			(start -0.12065 -0.305054)
			(end -0.12065 -0.2794)
			(stroke
				(width 0.1)
				(type default)
			)
			(layer "F.Fab")
		)
		(pad "1" smd circle
			(at -0.40005 0 270)
			(size 0 0)
			(layers "F.Cu" "F.Mask" "F.Paste")
			(net "GND")
		)
		(pad "2" smd circle
			(at 0.40005 0 270)
			(size 0 0)
			(layers "F.Cu" "F.Mask" "F.Paste")
			(net "DUALPORT_N_SSD5")
		)
	)
	(footprint ""
		(layer "F.Cu")
		(at 18.787872 -168.679368 90)
		(property "Reference" "PC19"
			(at 0 0 90)
			(layer "F.SilkS")
			(hide yes)
			(effects
				(font
					(size 1.27 1.27)
				)
			)
		)
		(property "Value" ""
			(at 0 0 90)
			(layer "F.Fab")
			(effects
				(font
					(size 1.27 1.27)
				)
			)
		)
		(duplicate_pad_numbers_are_jumpers no)
		(fp_line
			(start 0.7874 -0.4064)
			(end 0.7874 0.4064)
			(stroke
				(width 0.1524)
				(type default)
			)
			(layer "F.SilkS")
		)
		(fp_line
			(start -0.7874 -0.4064)
			(end 0.7874 -0.4064)
			(stroke
				(width 0.1524)
				(type default)
			)
			(layer "F.SilkS")
		)
		(fp_line
			(start 0.7874 0.4064)
			(end -0.7874 0.4064)
			(stroke
				(width 0.1524)
				(type default)
			)
			(layer "F.SilkS")
		)
		(fp_line
			(start -0.7874 0.4064)
			(end -0.7874 -0.4064)
			(stroke
				(width 0.1524)
				(type default)
			)
			(layer "F.SilkS")
		)
		(fp_line
			(start -0.12065 -0.305054)
			(end -0.12065 -0.2794)
			(stroke
				(width 0.1)
				(type default)
			)
			(layer "F.Fab")
		)
		(fp_line
			(start -0.67945 -0.305054)
			(end -0.12065 -0.305054)
			(stroke
				(width 0.1)
				(type default)
			)
			(layer "F.Fab")
		)
		(fp_line
			(start 0.67945 -0.3048)
			(end 0.67945 0.3048)
			(stroke
				(width 0.1)
				(type default)
			)
			(layer "F.Fab")
		)
		(fp_line
			(start 0.12065 -0.3048)
			(end 0.67945 -0.3048)
			(stroke
				(width 0.1)
				(type default)
			)
			(layer "F.Fab")
		)
		(fp_line
			(start 0.12065 -0.2794)
			(end 0.12065 -0.3048)
			(stroke
				(width 0.1)
				(type default)
			)
			(layer "F.Fab")
		)
		(fp_line
			(start -0.12065 -0.2794)
			(end 0.12065 -0.2794)
			(stroke
				(width 0.1)
				(type default)
			)
			(layer "F.Fab")
		)
		(fp_line
			(start 0.120396 0.2794)
			(end -0.12065 0.2794)
			(stroke
				(width 0.1)
				(type default)
			)
			(layer "F.Fab")
		)
		(fp_line
			(start -0.12065 0.2794)
			(end -0.12065 0.3048)
			(stroke
				(width 0.1)
				(type default)
			)
			(layer "F.Fab")
		)
		(fp_line
			(start 0.67945 0.3048)
			(end 0.120396 0.3048)
			(stroke
				(width 0.1)
				(type default)
			)
			(layer "F.Fab")
		)
		(fp_line
			(start 0.120396 0.3048)
			(end 0.120396 0.2794)
			(stroke
				(width 0.1)
				(type default)
			)
			(layer "F.Fab")
		)
		(fp_line
			(start -0.12065 0.3048)
			(end -0.67945 0.3048)
			(stroke
				(width 0.1)
				(type default)
			)
			(layer "F.Fab")
		)
		(fp_line
			(start -0.67945 0.3048)
			(end -0.67945 -0.305054)
			(stroke
				(width 0.1)
				(type default)
			)
			(layer "F.Fab")
		)
		(pad "1" smd circle
			(at -0.40005 0 90)
			(size 0 0)
			(layers "F.Cu" "F.Mask" "F.Paste")
			(net "SW_P5V_AUX_BT")
		)
		(pad "2" smd circle
			(at 0.40005 0 90)
			(size 0 0)
			(layers "F.Cu" "F.Mask" "F.Paste")
			(net "SW_P5V_AUX_PH")
		)
	)
	(footprint ""
		(layer "F.Cu")
		(at 182.548784 -198.109332 180)
		(property "Reference" "C2096"
			(at 0 0 180)
			(layer "F.SilkS")
			(hide yes)
			(effects
				(font
					(size 1.27 1.27)
				)
			)
		)
		(property "Value" ""
			(at 0 0 180)
			(layer "F.Fab")
			(effects
				(font
					(size 1.27 1.27)
				)
			)
		)
		(duplicate_pad_numbers_are_jumpers no)
		(fp_line
			(start 0.7874 0.4064)
			(end -0.7874 0.4064)
			(stroke
				(width 0.1524)
				(type default)
			)
			(layer "F.SilkS")
		)
		(fp_line
			(start 0.7874 -0.4064)
			(end 0.7874 0.4064)
			(stroke
				(width 0.1524)
				(type default)
			)
			(layer "F.SilkS")
		)
		(fp_line
			(start -0.7874 0.4064)
			(end -0.7874 -0.4064)
			(stroke
				(width 0.1524)
				(type default)
			)
			(layer "F.SilkS")
		)
		(fp_line
			(start -0.7874 -0.4064)
			(end 0.7874 -0.4064)
			(stroke
				(width 0.1524)
				(type default)
			)
			(layer "F.SilkS")
		)
		(fp_line
			(start 0.67945 0.3048)
			(end 0.120396 0.3048)
			(stroke
				(width 0.1)
				(type default)
			)
			(layer "F.Fab")
		)
		(fp_line
			(start 0.67945 -0.3048)
			(end 0.67945 0.3048)
			(stroke
				(width 0.1)
				(type default)
			)
			(layer "F.Fab")
		)
		(fp_line
			(start 0.12065 -0.2794)
			(end 0.12065 -0.3048)
			(stroke
				(width 0.1)
				(type default)
			)
			(layer "F.Fab")
		)
		(fp_line
			(start 0.12065 -0.3048)
			(end 0.67945 -0.3048)
			(stroke
				(width 0.1)
				(type default)
			)
			(layer "F.Fab")
		)
		(fp_line
			(start 0.120396 0.3048)
			(end 0.120396 0.2794)
			(stroke
				(width 0.1)
				(type default)
			)
			(layer "F.Fab")
		)
		(fp_line
			(start 0.120396 0.2794)
			(end -0.12065 0.2794)
			(stroke
				(width 0.1)
				(type default)
			)
			(layer "F.Fab")
		)
		(fp_line
			(start -0.12065 0.3048)
			(end -0.67945 0.3048)
			(stroke
				(width 0.1)
				(type default)
			)
			(layer "F.Fab")
		)
		(fp_line
			(start -0.12065 0.2794)
			(end -0.12065 0.3048)
			(stroke
				(width 0.1)
				(type default)
			)
			(layer "F.Fab")
		)
		(fp_line
			(start -0.12065 -0.2794)
			(end 0.12065 -0.2794)
			(stroke
				(width 0.1)
				(type default)
			)
			(layer "F.Fab")
		)
		(fp_line
			(start -0.12065 -0.305054)
			(end -0.12065 -0.2794)
			(stroke
				(width 0.1)
				(type default)
			)
			(layer "F.Fab")
		)
		(fp_line
			(start -0.67945 0.3048)
			(end -0.67945 -0.305054)
			(stroke
				(width 0.1)
				(type default)
			)
			(layer "F.Fab")
		)
		(fp_line
			(start -0.67945 -0.305054)
			(end -0.12065 -0.305054)
			(stroke
				(width 0.1)
				(type default)
			)
			(layer "F.Fab")
		)
		(pad "1" smd circle
			(at -0.40005 0 180)
			(size 0 0)
			(layers "F.Cu" "F.Mask" "F.Paste")
			(net "GND")
		)
		(pad "2" smd circle
			(at 0.40005 0 180)
			(size 0 0)
			(layers "F.Cu" "F.Mask" "F.Paste")
			(net "P3V3_AUX")
		)
	)
	(footprint ""
		(layer "F.Cu")
		(at 405.950166 -50.96383 180)
		(property "Reference" "PC575"
			(at 0 0 180)
			(layer "F.SilkS")
			(hide yes)
			(effects
				(font
					(size 1.27 1.27)
				)
			)
		)
		(property "Value" ""
			(at 0 0 180)
			(layer "F.Fab")
			(effects
				(font
					(size 1.27 1.27)
				)
			)
		)
		(duplicate_pad_numbers_are_jumpers no)
		(fp_line
			(start 1.524 0.762)
			(end -1.524 0.762)
			(stroke
				(width 0.1524)
				(type default)
			)
			(layer "F.SilkS")
		)
		(fp_line
			(start 1.524 -0.762)
			(end 1.524 0.762)
			(stroke
				(width 0.1524)
				(type default)
			)
			(layer "F.SilkS")
		)
		(fp_line
			(start -1.524 0.762)
			(end -1.524 -0.762)
			(stroke
				(width 0.1524)
				(type default)
			)
			(layer "F.SilkS")
		)
		(fp_line
			(start -1.524 -0.762)
			(end 1.524 -0.762)
			(stroke
				(width 0.1524)
				(type default)
			)
			(layer "F.SilkS")
		)
		(fp_line
			(start 1.1049 0.724916)
			(end 1.1049 -0.724916)
			(stroke
				(width 0.1)
				(type default)
			)
			(layer "F.Fab")
		)
		(fp_line
			(start 1.1049 -0.724916)
			(end -1.1049 -0.724916)
			(stroke
				(width 0.1)
				(type default)
			)
			(layer "F.Fab")
		)
		(fp_line
			(start -1.1049 0.724916)
			(end 1.1049 0.724916)
			(stroke
				(width 0.1)
				(type default)
			)
			(layer "F.Fab")
		)
		(fp_line
			(start -1.1049 -0.724916)
			(end -1.1049 0.724916)
			(stroke
				(width 0.1)
				(type default)
			)
			(layer "F.Fab")
		)
		(pad "1" smd rect
			(at -0.889 0)
			(size 1.016 1.27)
			(layers "F.Cu" "F.Mask" "F.Paste")
			(net "P3V3_SSD14")
		)
		(pad "2" smd rect
			(at 0.889 0)
			(size 1.016 1.27)
			(layers "F.Cu" "F.Mask" "F.Paste")
			(net "GND")
		)
	)
)
